# T6G (Grand Teton) — schematic netlist excerpt (pin names and nets, part order shuffled) for the footprints in the layout excerpt that follows; sources: Cadence DE-HDL packaged netlist, KiCad conversion of 04192023_DAF0TMB3IC0_F0TG_MB_C_brd_V02_OCP.brd

PPQ8  MOSFET_NCH_1D3S  PSMNR58-30YLH IC  pkg SOT1023  page 266
  \1\  = P12V_AUX
  \2\  = P12V_AUX
  \3\  = P12V_AUX
  \4\  = P12V_HSC_GATE_G4
  \5\  = P12V_MAIN_R

R2410  Q_RES  33.2 1% CHIP  pkg 0402LF  page 148 : A = SMB_M2_P1_1V8AUX_SDA_R ; B = SMB_M2_P1_1V8AUX_SDA

(kicad_pcb
	(version 20260206)
	(generator "pcbnew")
	(generator_version "10.0")
	(general
		(thickness 1.6)
		(legacy_teardrops no)
	)
	(paper "A4")
	(title_block
		(title "04192023_DAF0TMB3IC0_F0TG_MB_C_brd_V02_OCP.brd")
		(comment 1 "Grand Teton / footprints 4151-4152 of 8354")
	)
	(layers
		(0 "F.Cu" signal "TOP")
		(4 "In1.Cu" signal "GND")
		(6 "In2.Cu" signal "IN1")
		(8 "In3.Cu" signal "GND1")
		(10 "In4.Cu" signal "IN2")
		(12 "In5.Cu" signal "GND2")
		(14 "In6.Cu" signal "IN3")
		(16 "In7.Cu" signal "GND3")
		(18 "In8.Cu" signal "VCC")
		(20 "In9.Cu" signal "VCC1")
		(22 "In10.Cu" signal "GND4")
		(24 "In11.Cu" signal "IN4")
		(26 "In12.Cu" signal "GND5")
		(28 "In13.Cu" signal "IN5")
		(30 "In14.Cu" signal "GND6")
		(32 "In15.Cu" signal "IN6")
		(34 "In16.Cu" signal "GND7")
		(2 "B.Cu" signal "BOTTOM")
		(9 "F.Adhes" user "F.Adhesive")
		(11 "B.Adhes" user "B.Adhesive")
		(13 "F.Paste" user "Package Geometry/Pastemask Top")
		(15 "B.Paste" user "Package Geometry/Pastemask Bottom")
		(5 "F.SilkS" user "Ref Des/Silkscreen Top")
		(7 "B.SilkS" user "Ref Des/Silkscreen Bottom")
		(1 "F.Mask" user "Board Geometry/Soldermask Top")
		(3 "B.Mask" user "Board Geometry/Soldermask Bottom")
		(17 "Dwgs.User" user "User.Drawings")
		(19 "Cmts.User" user "User.Comments")
		(21 "Eco1.User" user "User.Eco1")
		(23 "Eco2.User" user "User.Eco2")
		(25 "Edge.Cuts" user "Board Geometry/Outline")
		(27 "Margin" user)
		(31 "F.CrtYd" user "Package Geometry/Place Bound Top")
		(29 "B.CrtYd" user "Package Geometry/Place Bound Bottom")
		(35 "F.Fab" user "Ref Des/Assembly Top")
		(33 "B.Fab" user "Ref Des/Assembly Bottom")
	)
	(footprint ""
		(layer "F.Cu")
		(at 146.304762 -41.746424 180)
		(property "Reference" "R2410"
			(at 0 0 180)
			(layer "F.SilkS")
			(hide yes)
			(effects
				(font
					(size 1.27 1.27)
				)
			)
		)
		(property "Value" ""
			(at 0 0 180)
			(layer "F.Fab")
			(effects
				(font
					(size 1.27 1.27)
				)
			)
		)
		(duplicate_pad_numbers_are_jumpers no)
		(fp_line
			(start 0.7874 0.4064)
			(end -0.7874 0.4064)
			(stroke
				(width 0.1524)
				(type default)
			)
			(layer "F.SilkS")
		)
		(fp_line
			(start 0.7874 -0.4064)
			(end 0.7874 0.4064)
			(stroke
				(width 0.1524)
				(type default)
			)
			(layer "F.SilkS")
		)
		(fp_line
			(start -0.7874 0.4064)
			(end -0.7874 -0.4064)
			(stroke
				(width 0.1524)
				(type default)
			)
			(layer "F.SilkS")
		)
		(fp_line
			(start -0.7874 -0.4064)
			(end 0.7874 -0.4064)
			(stroke
				(width 0.1524)
				(type default)
			)
			(layer "F.SilkS")
		)
		(fp_line
			(start 0.67945 0.3048)
			(end 0.120396 0.3048)
			(stroke
				(width 0.1)
				(type default)
			)
			(layer "F.Fab")
		)
		(fp_line
			(start 0.67945 -0.3048)
			(end 0.67945 0.3048)
			(stroke
				(width 0.1)
				(type default)
			)
			(layer "F.Fab")
		)
		(fp_line
			(start 0.12065 -0.2794)
			(end 0.12065 -0.3048)
			(stroke
				(width 0.1)
				(type default)
			)
			(layer "F.Fab")
		)
		(fp_line
			(start 0.12065 -0.3048)
			(end 0.67945 -0.3048)
			(stroke
				(width 0.1)
				(type default)
			)
			(layer "F.Fab")
		)
		(fp_line
			(start 0.120396 0.3048)
			(end 0.120396 0.2794)
			(stroke
				(width 0.1)
				(type default)
			)
			(layer "F.Fab")
		)
		(fp_line
			(start 0.120396 0.2794)
			(end -0.12065 0.2794)
			(stroke
				(width 0.1)
				(type default)
			)
			(layer "F.Fab")
		)
		(fp_line
			(start -0.12065 0.3048)
			(end -0.67945 0.3048)
			(stroke
				(width 0.1)
				(type default)
			)
			(layer "F.Fab")
		)
		(fp_line
			(start -0.12065 0.2794)
			(end -0.12065 0.3048)
			(stroke
				(width 0.1)
				(type default)
			)
			(layer "F.Fab")
		)
		(fp_line
			(start -0.12065 -0.2794)
			(end 0.12065 -0.2794)
			(stroke
				(width 0.1)
				(type default)
			)
			(layer "F.Fab")
		)
		(fp_line
			(start -0.12065 -0.305054)
			(end -0.12065 -0.2794)
			(stroke
				(width 0.1)
				(type default)
			)
			(layer "F.Fab")
		)
		(fp_line
			(start -0.67945 0.3048)
			(end -0.67945 -0.305054)
			(stroke
				(width 0.1)
				(type default)
			)
			(layer "F.Fab")
		)
		(fp_line
			(start -0.67945 -0.305054)
			(end -0.12065 -0.305054)
			(stroke
				(width 0.1)
				(type default)
			)
			(layer "F.Fab")
		)
		(pad "1" smd circle
			(at -0.40005 0 180)
			(size 0 0)
			(layers "F.Cu" "F.Mask" "F.Paste")
			(net "SMB_M2_P1_1V8AUX_SDA_R")
		)
		(pad "2" smd circle
			(at 0.40005 0 180)
			(size 0 0)
			(layers "F.Cu" "F.Mask" "F.Paste")
			(net "SMB_M2_P1_1V8AUX_SDA")
		)
	)
	(footprint ""
		(layer "F.Cu")
		(at 271.330928 -385.27736 90)
		(property "Reference" "PPQ8"
			(at -7.52348 -2.129028 0)
			(unlocked yes)
			(layer "F.SilkS")
			(effects
				(font
					(size 0.7874 0.5842)
					(thickness 0.1524)
				)
				(justify left)
			)
		)
		(property "Value" ""
			(at 0 0 90)
			(layer "F.Fab")
			(effects
				(font
					(size 1.27 1.27)
				)
			)
		)
		(duplicate_pad_numbers_are_jumpers no)
		(fp_line
			(start 2.350008 -2.649982)
			(end 2.350008 -2.4892)
			(stroke
				(width 0.1524)
				(type default)
			)
			(layer "F.SilkS")
		)
		(fp_line
			(start -2.350008 -2.649982)
			(end 2.350008 -2.649982)
			(stroke
				(width 0.1524)
				(type default)
			)
			(layer "F.SilkS")
		)
		(fp_line
			(start -2.350008 -2.4384)
			(end -2.350008 -2.649982)
			(stroke
				(width 0.1524)
				(type default)
			)
			(layer "F.SilkS")
		)
		(fp_line
			(start 2.350008 2.4892)
			(end 2.350008 2.649982)
			(stroke
				(width 0.1524)
				(type default)
			)
			(layer "F.SilkS")
		)
		(fp_line
			(start 2.350008 2.649982)
			(end -2.350008 2.649982)
			(stroke
				(width 0.1524)
				(type default)
			)
			(layer "F.SilkS")
		)
		(fp_line
			(start -2.350008 2.649982)
			(end -2.350008 2.413)
			(stroke
				(width 0.1524)
				(type default)
			)
			(layer "F.SilkS")
		)
		(fp_poly
			(pts
				(xy -3.457448 -3.442462) (xy -2.657602 -3.424174) (xy -3.100324 -2.39268)
			)
			(stroke
				(width 0)
				(type default)
			)
			(fill yes)
			(layer "F.SilkS")
		)
		(fp_line
			(start 2.350008 -2.649982)
			(end 2.350008 2.649982)
			(stroke
				(width 0.1)
				(type default)
			)
			(layer "F.Fab")
		)
		(fp_line
			(start -2.350008 -2.649982)
			(end 2.350008 -2.649982)
			(stroke
				(width 0.1)
				(type default)
			)
			(layer "F.Fab")
		)
		(fp_line
			(start 2.350008 2.649982)
			(end -2.350008 2.649982)
			(stroke
				(width 0.1)
				(type default)
			)
			(layer "F.Fab")
		)
		(fp_line
			(start -2.350008 2.649982)
			(end -2.350008 -2.649982)
			(stroke
				(width 0.1)
				(type default)
			)
			(layer "F.Fab")
		)
		(fp_poly
			(pts
				(xy -3.717544 -1.905) (xy -4.758944 -2.3241) (xy -4.758944 -1.524)
			)
			(stroke
				(width 0)
				(type default)
			)
			(fill yes)
			(layer "F.Fab")
		)
		(pad "1" smd rect
			(at -2.999994 -1.905)
			(size 0.7112 1.1684)
			(layers "F.Cu" "F.Mask" "F.Paste")
			(net "P12V_AUX")
		)
		(pad "2" smd rect
			(at -2.999994 -0.635)
			(size 0.7112 1.1684)
			(layers "F.Cu" "F.Mask" "F.Paste")
			(net "P12V_AUX")
		)
		(pad "3" smd rect
			(at -2.999994 0.635)
			(size 0.7112 1.1684)
			(layers "F.Cu" "F.Mask" "F.Paste")
			(net "P12V_AUX")
		)
		(pad "4" smd rect
			(at -2.999994 1.905)
			(size 0.7112 1.1684)
			(layers "F.Cu" "F.Mask" "F.Paste")
			(net "P12V_HSC_GATE_G4")
		)
		(pad "5" smd circle
			(at 0.925068 0)
			(size 0 0)
			(layers "F.Cu" "F.Mask" "F.Paste")
			(net "P12V_MAIN_R")
		)
		(zone
			(layer "F.Cu")
			(hatch none 0.5)
			(connect_pads
				(clearance 0)
			)
			(min_thickness 0.25)
			(keepout
				(tracks not_allowed)
				(vias allowed)
				(pads allowed)
				(copperpour not_allowed)
				(footprints allowed)
			)
			(placement
				(enabled no)
				(sheetname "")
			)
			(fill
				(thermal_gap 0.5)
				(thermal_bridge_width 0.5)
				(island_removal_mode 0)
			)
			(polygon
				(pts
					(xy 268.689328 -383.7178) (xy 273.972528 -383.7178) (xy 273.972528 -382.92786) (xy 268.689328 -382.92786)
				)
			)
		)
	)
)
